(kicad_pcb
	(version 20260206)
	(generator "pcbnew")
	(generator_version "10.0")
	(general
		(thickness 1.6)
		(legacy_teardrops no)
	)
	(paper "A4")
	(title_block
		(title "Wiwynn_Tioga_Pass_MB.brd")
		(comment 1 "Tioga Pass / footprints 2996-3002 of 4770")
	)
	(layers
		(0 "F.Cu" signal "TOP")
		(4 "In1.Cu" signal "L2GND")
		(6 "In2.Cu" signal "L3")
		(8 "In3.Cu" signal "L4GND")
		(10 "In4.Cu" signal "L5")
		(12 "In5.Cu" signal "L6GND")
		(14 "In6.Cu" signal "L7VCC")
		(16 "In7.Cu" signal "L8VCC")
		(18 "In8.Cu" signal "L9GND")
		(20 "In9.Cu" signal "L10")
		(22 "In10.Cu" signal "L11GND")
		(24 "In11.Cu" signal "L12")
		(26 "In12.Cu" signal "L13GND")
		(2 "B.Cu" signal "BOTTOM")
		(9 "F.Adhes" user "F.Adhesive")
		(11 "B.Adhes" user "B.Adhesive")
		(13 "F.Paste" user "Package Geometry/Pastemask Top")
		(15 "B.Paste" user "Package Geometry/Pastemask Bottom")
		(5 "F.SilkS" user "Ref Des/Silkscreen Top")
		(7 "B.SilkS" user "Ref Des/Silkscreen Bottom")
		(1 "F.Mask" user "Board Geometry/Soldermask Top")
		(3 "B.Mask" user "Board Geometry/Soldermask Bottom")
		(17 "Dwgs.User" user "User.Drawings")
		(19 "Cmts.User" user "User.Comments")
		(21 "Eco1.User" user "User.Eco1")
		(23 "Eco2.User" user "User.Eco2")
		(25 "Edge.Cuts" user "Board Geometry/Outline")
		(27 "Margin" user)
		(31 "F.CrtYd" user "Package Geometry/Place Bound Top")
		(29 "B.CrtYd" user "Package Geometry/Place Bound Bottom")
		(35 "F.Fab" user "Ref Des/Assembly Top")
		(33 "B.Fab" user "Ref Des/Assembly Bottom")
	)
	(footprint ""
		(layer "B.Cu")
		(at 451.517512 -15.84833 -90)
		(property "Reference" "CR3W1"
			(at -1.06934 -0.39116 0)
			(unlocked yes)
			(layer "B.SilkS")
			(effects
				(font
					(size 0.4064 0.254)
					(thickness 0.1524)
				)
				(justify left mirror)
			)
		)
		(property "Value" ""
			(at 0 0 90)
			(layer "B.Fab")
			(effects
				(font
					(size 1.27 1.27)
				)
				(justify mirror)
			)
		)
		(duplicate_pad_numbers_are_jumpers no)
		(fp_line
			(start 1.335278 2.576068)
			(end 1.335278 1.664462)
			(stroke
				(width 0.1524)
				(type default)
			)
			(layer "B.SilkS")
		)
		(fp_line
			(start 0.854456 1.664462)
			(end 1.335278 1.664462)
			(stroke
				(width 0.1524)
				(type default)
			)
			(layer "B.SilkS")
		)
		(fp_line
			(start 1.335278 1.664462)
			(end 1.8161 1.664462)
			(stroke
				(width 0.1524)
				(type default)
			)
			(layer "B.SilkS")
		)
		(fp_line
			(start 1.8161 1.664462)
			(end 1.335278 0.831596)
			(stroke
				(width 0.1524)
				(type default)
			)
			(layer "B.SilkS")
		)
		(fp_line
			(start 0.854456 0.831596)
			(end 1.8161 0.831596)
			(stroke
				(width 0.1524)
				(type default)
			)
			(layer "B.SilkS")
		)
		(fp_line
			(start 1.335278 0.831596)
			(end 0.854456 1.664462)
			(stroke
				(width 0.1524)
				(type default)
			)
			(layer "B.SilkS")
		)
		(fp_line
			(start 1.335278 -0.291846)
			(end 1.335278 0.831596)
			(stroke
				(width 0.1524)
				(type default)
			)
			(layer "B.SilkS")
		)
		(fp_poly
			(pts
				(xy 0.67437 0.24384) (xy 0.67437 2.04216) (xy -0.67437 2.04216) (xy -0.67437 0.24384)
			)
			(stroke
				(width 0)
				(type default)
			)
			(fill no)
			(layer "B.CrtYd")
		)
		(fp_line
			(start -0.67437 2.04216)
			(end -0.67437 0.24384)
			(stroke
				(width 0.1)
				(type default)
			)
			(layer "B.Fab")
		)
		(fp_line
			(start 0.67437 2.04216)
			(end -0.67437 2.04216)
			(stroke
				(width 0.1)
				(type default)
			)
			(layer "B.Fab")
		)
		(fp_line
			(start 0.854456 1.664462)
			(end 1.8161 1.664462)
			(stroke
				(width 0.1)
				(type default)
			)
			(layer "B.Fab")
		)
		(fp_line
			(start 1.335278 1.664462)
			(end 1.335278 2.576068)
			(stroke
				(width 0.1)
				(type default)
			)
			(layer "B.Fab")
		)
		(fp_line
			(start 1.8161 1.664462)
			(end 1.335278 0.831596)
			(stroke
				(width 0.1)
				(type default)
			)
			(layer "B.Fab")
		)
		(fp_line
			(start 0.854456 0.831596)
			(end 1.8161 0.831596)
			(stroke
				(width 0.1)
				(type default)
			)
			(layer "B.Fab")
		)
		(fp_line
			(start 1.335278 0.831596)
			(end 0.854456 1.664462)
			(stroke
				(width 0.1)
				(type default)
			)
			(layer "B.Fab")
		)
		(fp_line
			(start 1.335278 0.831596)
			(end 1.335278 -0.291846)
			(stroke
				(width 0.1)
				(type default)
			)
			(layer "B.Fab")
		)
		(fp_line
			(start -0.67437 0.24384)
			(end 0.67437 0.24384)
			(stroke
				(width 0.1)
				(type default)
			)
			(layer "B.Fab")
		)
		(fp_line
			(start 0.67437 0.24384)
			(end 0.67437 2.04216)
			(stroke
				(width 0.1)
				(type default)
			)
			(layer "B.Fab")
		)
		(pad "1" smd rect
			(at 0 0 90)
			(size 0.4064 1.016)
			(layers "B.Cu" "B.Mask" "B.Paste")
			(net "BMC_SELF_HW_D_RST")
		)
		(pad "2" smd rect
			(at 0 2.286 90)
			(size 0.4064 1.016)
			(layers "B.Cu" "B.Mask" "B.Paste")
			(net "BMC_SELF_HW_RST")
		)
	)
	(footprint ""
		(layer "B.Cu")
		(at 174.6123 -3.683 -90)
		(property "Reference" "R6U7"
			(at 0 0 90)
			(layer "B.SilkS")
			(hide yes)
			(effects
				(font
					(size 1.27 1.27)
				)
				(justify mirror)
			)
		)
		(property "Value" ""
			(at 0 0 90)
			(layer "B.Fab")
			(effects
				(font
					(size 1.27 1.27)
				)
				(justify mirror)
			)
		)
		(duplicate_pad_numbers_are_jumpers no)
		(fp_rect
			(start -0.2794 -0.1016)
			(end 0.2794 0.9906)
			(stroke
				(width 0)
				(type default)
			)
			(fill no)
			(layer "B.CrtYd")
		)
		(fp_line
			(start -0.2794 0.9906)
			(end -0.2794 -0.1016)
			(stroke
				(width 0.1)
				(type default)
			)
			(layer "B.Fab")
		)
		(fp_line
			(start 0.2794 0.9906)
			(end -0.2794 0.9906)
			(stroke
				(width 0.1)
				(type default)
			)
			(layer "B.Fab")
		)
		(fp_line
			(start -0.2794 -0.1016)
			(end 0.2794 -0.1016)
			(stroke
				(width 0.1)
				(type default)
			)
			(layer "B.Fab")
		)
		(fp_line
			(start 0.2794 -0.1016)
			(end 0.2794 0.9906)
			(stroke
				(width 0.1)
				(type default)
			)
			(layer "B.Fab")
		)
		(pad "1" smd rect
			(at 0 0 90)
			(size 0.508 0.508)
			(layers "B.Cu" "B.Mask" "B.Paste")
			(net "P3V3")
		)
		(pad "2" smd rect
			(at 0 0.889 90)
			(size 0.508 0.508)
			(layers "B.Cu" "B.Mask" "B.Paste")
			(net "VR_PVTT_GHJ_BIAS")
		)
		(zone
			(layer "B.Cu")
			(hatch none 0.5)
			(connect_pads
				(clearance 0)
			)
			(min_thickness 0.25)
			(keepout
				(tracks not_allowed)
				(vias allowed)
				(pads allowed)
				(copperpour not_allowed)
				(footprints allowed)
			)
			(placement
				(enabled no)
				(sheetname "")
			)
			(fill
				(thermal_gap 0.5)
				(thermal_bridge_width 0.5)
				(island_removal_mode 0)
			)
			(polygon
				(pts
					(xy 174.3583 -3.937) (xy 173.9773 -3.937) (xy 173.9773 -3.429) (xy 174.3583 -3.429)
				)
			)
		)
		(zone
			(layer "B.Cu")
			(hatch none 0.5)
			(connect_pads
				(clearance 0)
			)
			(min_thickness 0.25)
			(keepout
				(tracks allowed)
				(vias not_allowed)
				(pads allowed)
				(copperpour not_allowed)
				(footprints allowed)
			)
			(placement
				(enabled no)
				(sheetname "")
			)
			(fill
				(thermal_gap 0.5)
				(thermal_bridge_width 0.5)
				(island_removal_mode 0)
			)
			(polygon
				(pts
					(xy 174.3583 -3.937) (xy 173.9773 -3.937) (xy 173.9773 -3.429) (xy 174.3583 -3.429)
				)
			)
		)
	)
	(footprint ""
		(layer "B.Cu")
		(at 392.43 -87.4395)
		(property "Reference" "R8D20"
			(at 0.8382 -0.67818 0)
			(unlocked yes)
			(layer "B.SilkS")
			(effects
				(font
					(size 0.4064 0.254)
					(thickness 0.1524)
				)
				(justify left mirror)
			)
		)
		(property "Value" ""
			(at 0 0 0)
			(layer "B.Fab")
			(effects
				(font
					(size 1.27 1.27)
				)
				(justify mirror)
			)
		)
		(duplicate_pad_numbers_are_jumpers no)
		(fp_poly
			(pts
				(xy 0.2794 -0.1016) (xy -0.2794 -0.1016) (xy -0.2794 0.9906) (xy 0.2794 0.9906)
			)
			(stroke
				(width 0)
				(type default)
			)
			(fill no)
			(layer "B.CrtYd")
		)
		(fp_line
			(start -0.2794 -0.1016)
			(end 0.2794 -0.1016)
			(stroke
				(width 0.1)
				(type default)
			)
			(layer "B.Fab")
		)
		(fp_line
			(start -0.2794 0.9906)
			(end -0.2794 -0.1016)
			(stroke
				(width 0.1)
				(type default)
			)
			(layer "B.Fab")
		)
		(fp_line
			(start 0.2794 -0.1016)
			(end 0.2794 0.9906)
			(stroke
				(width 0.1)
				(type default)
			)
			(layer "B.Fab")
		)
		(fp_line
			(start 0.2794 0.9906)
			(end -0.2794 0.9906)
			(stroke
				(width 0.1)
				(type default)
			)
			(layer "B.Fab")
		)
		(pad "1" smd rect
			(at 0 0 180)
			(size 0.508 0.508)
			(layers "B.Cu" "B.Mask" "B.Paste")
			(net "SGPIO_PCH_SATA_LOAD")
		)
		(pad "2" smd rect
			(at 0 0.889 180)
			(size 0.508 0.508)
			(layers "B.Cu" "B.Mask" "B.Paste")
			(net "SGPIO_PCH_SATA_LOAD_R")
		)
		(zone
			(layer "B.Cu")
			(hatch none 0.5)
			(connect_pads
				(clearance 0)
			)
			(min_thickness 0.25)
			(keepout
				(tracks allowed)
				(vias not_allowed)
				(pads allowed)
				(copperpour not_allowed)
				(footprints allowed)
			)
			(placement
				(enabled no)
				(sheetname "")
			)
			(fill
				(thermal_gap 0.5)
				(thermal_bridge_width 0.5)
				(island_removal_mode 0)
			)
			(polygon
				(pts
					(xy 392.684 -87.1855) (xy 392.176 -87.1855) (xy 392.176 -86.8045) (xy 392.684 -86.8045)
				)
			)
		)
		(zone
			(layer "B.Cu")
			(hatch none 0.5)
			(connect_pads
				(clearance 0)
			)
			(min_thickness 0.25)
			(keepout
				(tracks not_allowed)
				(vias allowed)
				(pads allowed)
				(copperpour not_allowed)
				(footprints allowed)
			)
			(placement
				(enabled no)
				(sheetname "")
			)
			(fill
				(thermal_gap 0.5)
				(thermal_bridge_width 0.5)
				(island_removal_mode 0)
			)
			(polygon
				(pts
					(xy 392.684 -86.8045) (xy 392.176 -86.8045) (xy 392.176 -87.1855) (xy 392.684 -87.1855)
				)
			)
		)
	)
	(footprint ""
		(layer "B.Cu")
		(at 348.574614 -123.576842 -90)
		(property "Reference" "R774"
			(at 0.8382 -0.67818 270)
			(unlocked yes)
			(layer "B.SilkS")
			(effects
				(font
					(size 0.4064 0.254)
					(thickness 0.1524)
				)
				(justify left mirror)
			)
		)
		(property "Value" ""
			(at 0 0 90)
			(layer "B.Fab")
			(effects
				(font
					(size 1.27 1.27)
				)
				(justify mirror)
			)
		)
		(duplicate_pad_numbers_are_jumpers no)
		(fp_poly
			(pts
				(xy 0.2794 -0.1016) (xy -0.2794 -0.1016) (xy -0.2794 0.9906) (xy 0.2794 0.9906)
			)
			(stroke
				(width 0)
				(type default)
			)
			(fill no)
			(layer "B.CrtYd")
		)
		(fp_line
			(start -0.2794 0.9906)
			(end -0.2794 -0.1016)
			(stroke
				(width 0.1)
				(type default)
			)
			(layer "B.Fab")
		)
		(fp_line
			(start 0.2794 0.9906)
			(end -0.2794 0.9906)
			(stroke
				(width 0.1)
				(type default)
			)
			(layer "B.Fab")
		)
		(fp_line
			(start -0.2794 -0.1016)
			(end 0.2794 -0.1016)
			(stroke
				(width 0.1)
				(type default)
			)
			(layer "B.Fab")
		)
		(fp_line
			(start 0.2794 -0.1016)
			(end 0.2794 0.9906)
			(stroke
				(width 0.1)
				(type default)
			)
			(layer "B.Fab")
		)
		(pad "1" smd rect
			(at 0 0 90)
			(size 0.508 0.508)
			(layers "B.Cu" "B.Mask" "B.Paste")
			(net "P3E_CPU0_PE1_PCH_RXP<13>")
		)
		(pad "2" smd rect
			(at 0 0.889 90)
			(size 0.508 0.508)
			(layers "B.Cu" "B.Mask" "B.Paste")
			(net "P3E_CPU0_PE1_PCH_CON_RXP<13>")
		)
		(zone
			(layer "B.Cu")
			(hatch none 0.5)
			(connect_pads
				(clearance 0)
			)
			(min_thickness 0.25)
			(keepout
				(tracks not_allowed)
				(vias allowed)
				(pads allowed)
				(copperpour not_allowed)
				(footprints allowed)
			)
			(placement
				(enabled no)
				(sheetname "")
			)
			(fill
				(thermal_gap 0.5)
				(thermal_bridge_width 0.5)
				(island_removal_mode 0)
			)
			(polygon
				(pts
					(xy 347.939614 -123.322842) (xy 347.939614 -123.830842) (xy 348.320614 -123.830842) (xy 348.320614 -123.322842)
				)
			)
		)
		(zone
			(layer "B.Cu")
			(hatch none 0.5)
			(connect_pads
				(clearance 0)
			)
			(min_thickness 0.25)
			(keepout
				(tracks allowed)
				(vias not_allowed)
				(pads allowed)
				(copperpour not_allowed)
				(footprints allowed)
			)
			(placement
				(enabled no)
				(sheetname "")
			)
			(fill
				(thermal_gap 0.5)
				(thermal_bridge_width 0.5)
				(island_removal_mode 0)
			)
			(polygon
				(pts
					(xy 348.320614 -123.322842) (xy 348.320614 -123.830842) (xy 347.939614 -123.830842) (xy 347.939614 -123.322842)
				)
			)
		)
	)
	(footprint ""
		(layer "B.Cu")
		(at 401.472146 -40.598852 90)
		(property "Reference" "R2U4"
			(at 0 0 90)
			(layer "B.SilkS")
			(hide yes)
			(effects
				(font
					(size 1.27 1.27)
				)
				(justify mirror)
			)
		)
		(property "Value" ""
			(at 0 0 90)
			(layer "B.Fab")
			(effects
				(font
					(size 1.27 1.27)
				)
				(justify mirror)
			)
		)
		(duplicate_pad_numbers_are_jumpers no)
		(fp_poly
			(pts
				(xy 0.2794 -0.1016) (xy -0.2794 -0.1016) (xy -0.2794 0.9906) (xy 0.2794 0.9906)
			)
			(stroke
				(width 0)
				(type default)
			)
			(fill no)
			(layer "B.CrtYd")
		)
		(fp_line
			(start 0.2794 -0.1016)
			(end 0.2794 0.9906)
			(stroke
				(width 0.1)
				(type default)
			)
			(layer "B.Fab")
		)
		(fp_line
			(start -0.2794 -0.1016)
			(end 0.2794 -0.1016)
			(stroke
				(width 0.1)
				(type default)
			)
			(layer "B.Fab")
		)
		(fp_line
			(start 0.2794 0.9906)
			(end -0.2794 0.9906)
			(stroke
				(width 0.1)
				(type default)
			)
			(layer "B.Fab")
		)
		(fp_line
			(start -0.2794 0.9906)
			(end -0.2794 -0.1016)
			(stroke
				(width 0.1)
				(type default)
			)
			(layer "B.Fab")
		)
		(pad "1" smd rect
			(at 0 0 270)
			(size 0.508 0.508)
			(layers "B.Cu" "B.Mask" "B.Paste")
			(net "P3V3_STBY")
		)
		(pad "2" smd rect
			(at 0 0.889 270)
			(size 0.508 0.508)
			(layers "B.Cu" "B.Mask" "B.Paste")
			(net "FM_CPLD_BMC_PWRDN_N")
		)
		(zone
			(layer "B.Cu")
			(hatch none 0.5)
			(connect_pads
				(clearance 0)
			)
			(min_thickness 0.25)
			(keepout
				(tracks allowed)
				(vias not_allowed)
				(pads allowed)
				(copperpour not_allowed)
				(footprints allowed)
			)
			(placement
				(enabled no)
				(sheetname "")
			)
			(fill
				(thermal_gap 0.5)
				(thermal_bridge_width 0.5)
				(island_removal_mode 0)
			)
			(polygon
				(pts
					(xy 401.726146 -40.852852) (xy 401.726146 -40.344852) (xy 402.107146 -40.344852) (xy 402.107146 -40.852852)
				)
			)
		)
		(zone
			(layer "B.Cu")
			(hatch none 0.5)
			(connect_pads
				(clearance 0)
			)
			(min_thickness 0.25)
			(keepout
				(tracks not_allowed)
				(vias allowed)
				(pads allowed)
				(copperpour not_allowed)
				(footprints allowed)
			)
			(placement
				(enabled no)
				(sheetname "")
			)
			(fill
				(thermal_gap 0.5)
				(thermal_bridge_width 0.5)
				(island_removal_mode 0)
			)
			(polygon
				(pts
					(xy 402.107146 -40.852852) (xy 402.107146 -40.344852) (xy 401.726146 -40.344852) (xy 401.726146 -40.852852)
				)
			)
		)
	)
	(footprint ""
		(layer "B.Cu")
		(at 348.1578 -98.2218 -90)
		(property "Reference" "C3N34"
			(at 0 0 90)
			(layer "B.SilkS")
			(hide yes)
			(effects
				(font
					(size 1.27 1.27)
				)
				(justify mirror)
			)
		)
		(property "Value" ""
			(at 0 0 90)
			(layer "B.Fab")
			(effects
				(font
					(size 1.27 1.27)
				)
				(justify mirror)
			)
		)
		(duplicate_pad_numbers_are_jumpers no)
		(fp_poly
			(pts
				(xy 0.7239 -0.2159) (xy -0.7239 -0.2159) (xy -0.7239 1.9939) (xy 0.7239 1.9939)
			)
			(stroke
				(width 0)
				(type default)
			)
			(fill no)
			(layer "B.CrtYd")
		)
		(fp_line
			(start -0.7239 1.9939)
			(end -0.7239 -0.2159)
			(stroke
				(width 0.1)
				(type default)
			)
			(layer "B.Fab")
		)
		(fp_line
			(start 0.7239 1.9939)
			(end -0.7239 1.9939)
			(stroke
				(width 0.1)
				(type default)
			)
			(layer "B.Fab")
		)
		(fp_line
			(start -0.7239 -0.2159)
			(end 0.7239 -0.2159)
			(stroke
				(width 0.1)
				(type default)
			)
			(layer "B.Fab")
		)
		(fp_line
			(start 0.7239 -0.2159)
			(end 0.7239 1.9939)
			(stroke
				(width 0.1)
				(type default)
			)
			(layer "B.Fab")
		)
		(pad "1" smd rect
			(at 0 0 90)
			(size 1.27 1.016)
			(layers "B.Cu" "B.Mask" "B.Paste")
			(net "VR_FET_SW_P12V_STBY_PVCCIO_CPU0")
		)
		(pad "2" smd rect
			(at 0 1.778 90)
			(size 1.27 1.016)
			(layers "B.Cu" "B.Mask" "B.Paste")
			(net "GND")
		)
		(zone
			(layer "B.Cu")
			(hatch none 0.5)
			(connect_pads
				(clearance 0)
			)
			(min_thickness 0.25)
			(keepout
				(tracks not_allowed)
				(vias allowed)
				(pads allowed)
				(copperpour not_allowed)
				(footprints allowed)
			)
			(placement
				(enabled no)
				(sheetname "")
			)
			(fill
				(thermal_gap 0.5)
				(thermal_bridge_width 0.5)
				(island_removal_mode 0)
			)
			(polygon
				(pts
					(xy 347.6498 -97.5868) (xy 347.6498 -98.8568) (xy 346.8878 -98.8568) (xy 346.8878 -97.5868)
				)
			)
		)
	)
	(footprint ""
		(layer "B.Cu")
		(at 390.13765 -111.05515 180)
		(property "Reference" "C2N3"
			(at 0 0 0)
			(layer "B.SilkS")
			(hide yes)
			(effects
				(font
					(size 1.27 1.27)
				)
				(justify mirror)
			)
		)
		(property "Value" ""
			(at 0 0 0)
			(layer "B.Fab")
			(effects
				(font
					(size 1.27 1.27)
				)
				(justify mirror)
			)
		)
		(duplicate_pad_numbers_are_jumpers no)
		(fp_rect
			(start 0.2794 0.9144)
			(end -0.2794 -0.1143)
			(stroke
				(width 0)
				(type default)
			)
			(fill no)
			(layer "B.CrtYd")
		)
		(fp_line
			(start 0.2794 0.9144)
			(end 0.2794 -0.1143)
			(stroke
				(width 0.1)
				(type default)
			)
			(layer "B.Fab")
		)
		(fp_line
			(start 0.2794 -0.1143)
			(end -0.2794 -0.1143)
			(stroke
				(width 0.1)
				(type default)
			)
			(layer "B.Fab")
		)
		(fp_line
			(start -0.2794 0.9144)
			(end 0.2794 0.9144)
			(stroke
				(width 0.1)
				(type default)
			)
			(layer "B.Fab")
		)
		(fp_line
			(start -0.2794 -0.1143)
			(end -0.2794 0.9144)
			(stroke
				(width 0.1)
				(type default)
			)
			(layer "B.Fab")
		)
		(pad "1" smd custom
			(at 0 0 90)
			(size 0.10414 0.10414)
			(layers "B.Cu" "B.Mask" "B.Paste")
			(net "PVNN_PCH_STBY")
			(options
				(clearance outline)
				(anchor circle)
			)
			(primitives
				(gr_poly
					(pts
						(xy -0.20828 -0.08636) (xy -0.20828 0.08636) (xy -0.08636 0.20828) (xy 0.086614 0.20828) (xy 0.20828 0.086614)
						(xy 0.20828 -0.08636) (xy 0.08636 -0.20828) (xy -0.08636 -0.20828)
					)
					(width 0)
					(fill yes)
				)
			)
		)
		(pad "2" smd custom
			(at 0 0.8001 90)
			(size 0.10414 0.10414)
			(layers "B.Cu" "B.Mask" "B.Paste")
			(net "GND")
			(options
				(clearance outline)
				(anchor circle)
			)
			(primitives
				(gr_poly
					(pts
						(xy -0.20828 -0.08636) (xy -0.20828 0.08636) (xy -0.08636 0.20828) (xy 0.086614 0.20828) (xy 0.20828 0.086614)
						(xy 0.20828 -0.08636) (xy 0.08636 -0.20828) (xy -0.08636 -0.20828)
					)
					(width 0)
					(fill yes)
				)
			)
		)
		(zone
			(layer "B.Cu")
			(hatch none 0.5)
			(connect_pads
				(clearance 0)
			)
			(min_thickness 0.25)
			(keepout
				(tracks allowed)
				(vias not_allowed)
				(pads allowed)
				(copperpour not_allowed)
				(footprints allowed)
			)
			(placement
				(enabled no)
				(sheetname "")
			)
			(fill
				(thermal_gap 0.5)
				(thermal_bridge_width 0.5)
				(island_removal_mode 0)
			)
			(polygon
				(pts
					(xy 390.05002 -111.2647) (xy 390.05002 -111.6457) (xy 390.22528 -111.6457) (xy 390.225534 -111.2647)
				)
			)
		)
		(zone
			(layer "B.Cu")
			(hatch none 0.5)
			(connect_pads
				(clearance 0)
			)
			(min_thickness 0.25)
			(keepout
				(tracks not_allowed)
				(vias allowed)
				(pads allowed)
				(copperpour not_allowed)
				(footprints allowed)
			)
			(placement
				(enabled no)
				(sheetname "")
			)
			(fill
				(thermal_gap 0.5)
				(thermal_bridge_width 0.5)
				(island_removal_mode 0)
			)
			(polygon
				(pts
					(xy 390.05002 -111.2647) (xy 390.05002 -111.6457) (xy 390.22528 -111.6457) (xy 390.225534 -111.2647)
				)
			)
		)
	)
)
